(kicad_pcb
	(version 20260206)
	(generator "pcbnew")
	(generator_version "10.0")
	(general
		(thickness 1.6)
		(legacy_teardrops no)
	)
	(paper "A4")
	(title_block
		(title "Wiwynn_Tioga_Pass_MB.brd")
		(comment 1 "Tioga Pass / footprints 358-365 of 4770")
	)
	(layers
		(0 "F.Cu" signal "TOP")
		(4 "In1.Cu" signal "L2GND")
		(6 "In2.Cu" signal "L3")
		(8 "In3.Cu" signal "L4GND")
		(10 "In4.Cu" signal "L5")
		(12 "In5.Cu" signal "L6GND")
		(14 "In6.Cu" signal "L7VCC")
		(16 "In7.Cu" signal "L8VCC")
		(18 "In8.Cu" signal "L9GND")
		(20 "In9.Cu" signal "L10")
		(22 "In10.Cu" signal "L11GND")
		(24 "In11.Cu" signal "L12")
		(26 "In12.Cu" signal "L13GND")
		(2 "B.Cu" signal "BOTTOM")
		(9 "F.Adhes" user "F.Adhesive")
		(11 "B.Adhes" user "B.Adhesive")
		(13 "F.Paste" user "Package Geometry/Pastemask Top")
		(15 "B.Paste" user "Package Geometry/Pastemask Bottom")
		(5 "F.SilkS" user "Ref Des/Silkscreen Top")
		(7 "B.SilkS" user "Ref Des/Silkscreen Bottom")
		(1 "F.Mask" user "Board Geometry/Soldermask Top")
		(3 "B.Mask" user "Board Geometry/Soldermask Bottom")
		(17 "Dwgs.User" user "User.Drawings")
		(19 "Cmts.User" user "User.Comments")
		(21 "Eco1.User" user "User.Eco1")
		(23 "Eco2.User" user "User.Eco2")
		(25 "Edge.Cuts" user "Board Geometry/Outline")
		(27 "Margin" user)
		(31 "F.CrtYd" user "Package Geometry/Place Bound Top")
		(29 "B.CrtYd" user "Package Geometry/Place Bound Bottom")
		(35 "F.Fab" user "Ref Des/Assembly Top")
		(33 "B.Fab" user "Ref Des/Assembly Bottom")
	)
	(footprint ""
		(layer "F.Cu")
		(at 487.969306 -27.666696)
		(property "Reference" "R9F24"
			(at 0 0 0)
			(layer "F.SilkS")
			(hide yes)
			(effects
				(font
					(size 1.27 1.27)
				)
			)
		)
		(property "Value" ""
			(at 0 0 0)
			(layer "F.Fab")
			(effects
				(font
					(size 1.27 1.27)
				)
			)
		)
		(duplicate_pad_numbers_are_jumpers no)
		(fp_poly
			(pts
				(xy -0.2794 -0.1016) (xy 0.2794 -0.1016) (xy 0.2794 0.9906) (xy -0.2794 0.9906)
			)
			(stroke
				(width 0)
				(type default)
			)
			(fill no)
			(layer "F.CrtYd")
		)
		(fp_line
			(start -0.2794 -0.1016)
			(end -0.2794 0.9906)
			(stroke
				(width 0.1)
				(type default)
			)
			(layer "F.Fab")
		)
		(fp_line
			(start -0.2794 0.9906)
			(end 0.2794 0.9906)
			(stroke
				(width 0.1)
				(type default)
			)
			(layer "F.Fab")
		)
		(fp_line
			(start 0.2794 -0.1016)
			(end -0.2794 -0.1016)
			(stroke
				(width 0.1)
				(type default)
			)
			(layer "F.Fab")
		)
		(fp_line
			(start 0.2794 0.9906)
			(end 0.2794 -0.1016)
			(stroke
				(width 0.1)
				(type default)
			)
			(layer "F.Fab")
		)
		(pad "1" smd rect
			(at 0 0)
			(size 0.508 0.508)
			(layers "F.Cu" "F.Mask" "F.Paste")
			(net "SPA_MID_DBG_RX")
		)
		(pad "2" smd rect
			(at 0 0.889)
			(size 0.508 0.508)
			(layers "F.Cu" "F.Mask" "F.Paste")
			(net "SP2_BMC_CM_UART_RX")
		)
		(zone
			(layer "F.Cu")
			(hatch none 0.5)
			(connect_pads
				(clearance 0)
			)
			(min_thickness 0.25)
			(keepout
				(tracks allowed)
				(vias not_allowed)
				(pads allowed)
				(copperpour not_allowed)
				(footprints allowed)
			)
			(placement
				(enabled no)
				(sheetname "")
			)
			(fill
				(thermal_gap 0.5)
				(thermal_bridge_width 0.5)
				(island_removal_mode 0)
			)
			(polygon
				(pts
					(xy 487.715306 -27.412696) (xy 488.223306 -27.412696) (xy 488.223306 -27.031696) (xy 487.715306 -27.031696)
				)
			)
		)
		(zone
			(layer "F.Cu")
			(hatch none 0.5)
			(connect_pads
				(clearance 0)
			)
			(min_thickness 0.25)
			(keepout
				(tracks not_allowed)
				(vias allowed)
				(pads allowed)
				(copperpour not_allowed)
				(footprints allowed)
			)
			(placement
				(enabled no)
				(sheetname "")
			)
			(fill
				(thermal_gap 0.5)
				(thermal_bridge_width 0.5)
				(island_removal_mode 0)
			)
			(polygon
				(pts
					(xy 487.715306 -27.031696) (xy 488.223306 -27.031696) (xy 488.223306 -27.412696) (xy 487.715306 -27.412696)
				)
			)
		)
	)
	(footprint ""
		(layer "F.Cu")
		(at 164.846 -86.868 180)
		(property "Reference" "R4D1"
			(at 0 0 180)
			(layer "F.SilkS")
			(hide yes)
			(effects
				(font
					(size 1.27 1.27)
				)
			)
		)
		(property "Value" ""
			(at 0 0 180)
			(layer "F.Fab")
			(effects
				(font
					(size 1.27 1.27)
				)
			)
		)
		(duplicate_pad_numbers_are_jumpers no)
		(fp_poly
			(pts
				(xy -0.2794 -0.1016) (xy 0.2794 -0.1016) (xy 0.2794 0.9906) (xy -0.2794 0.9906)
			)
			(stroke
				(width 0)
				(type default)
			)
			(fill no)
			(layer "F.CrtYd")
		)
		(fp_line
			(start 0.2794 0.9906)
			(end 0.2794 -0.1016)
			(stroke
				(width 0.1)
				(type default)
			)
			(layer "F.Fab")
		)
		(fp_line
			(start 0.2794 -0.1016)
			(end -0.2794 -0.1016)
			(stroke
				(width 0.1)
				(type default)
			)
			(layer "F.Fab")
		)
		(fp_line
			(start -0.2794 0.9906)
			(end 0.2794 0.9906)
			(stroke
				(width 0.1)
				(type default)
			)
			(layer "F.Fab")
		)
		(fp_line
			(start -0.2794 -0.1016)
			(end -0.2794 0.9906)
			(stroke
				(width 0.1)
				(type default)
			)
			(layer "F.Fab")
		)
		(pad "1" smd rect
			(at 0 0 180)
			(size 0.508 0.508)
			(layers "F.Cu" "F.Mask" "F.Paste")
			(net "CLK_100M_CPU1_BCLK1_R_DN")
		)
		(pad "2" smd rect
			(at 0 0.889 180)
			(size 0.508 0.508)
			(layers "F.Cu" "F.Mask" "F.Paste")
			(net "CLK_100M_CPU1_BCLK1_DN")
		)
		(zone
			(layer "F.Cu")
			(hatch none 0.5)
			(connect_pads
				(clearance 0)
			)
			(min_thickness 0.25)
			(keepout
				(tracks not_allowed)
				(vias allowed)
				(pads allowed)
				(copperpour not_allowed)
				(footprints allowed)
			)
			(placement
				(enabled no)
				(sheetname "")
			)
			(fill
				(thermal_gap 0.5)
				(thermal_bridge_width 0.5)
				(island_removal_mode 0)
			)
			(polygon
				(pts
					(xy 165.1 -87.503) (xy 164.592 -87.503) (xy 164.592 -87.122) (xy 165.1 -87.122)
				)
			)
		)
		(zone
			(layer "F.Cu")
			(hatch none 0.5)
			(connect_pads
				(clearance 0)
			)
			(min_thickness 0.25)
			(keepout
				(tracks allowed)
				(vias not_allowed)
				(pads allowed)
				(copperpour not_allowed)
				(footprints allowed)
			)
			(placement
				(enabled no)
				(sheetname "")
			)
			(fill
				(thermal_gap 0.5)
				(thermal_bridge_width 0.5)
				(island_removal_mode 0)
			)
			(polygon
				(pts
					(xy 165.1 -87.122) (xy 164.592 -87.122) (xy 164.592 -87.503) (xy 165.1 -87.503)
				)
			)
		)
	)
	(footprint ""
		(layer "F.Cu")
		(at 382.708404 -158.248858 -90)
		(property "Reference" "CT67"
			(at -0.32893 -6.0706 0)
			(unlocked yes)
			(layer "F.SilkS")
			(effects
				(font
					(size 0.7874 0.5842)
					(thickness 0.1524)
				)
				(justify left)
			)
		)
		(property "Value" ""
			(at 0 0 270)
			(layer "F.Fab")
			(effects
				(font
					(size 1.27 1.27)
				)
			)
		)
		(duplicate_pad_numbers_are_jumpers no)
		(fp_poly
			(pts
				(xy 0.3048 -0.1016) (xy 0.3048 0.9906) (xy -0.3048 0.9906) (xy -0.3048 -0.1016)
			)
			(stroke
				(width 0)
				(type default)
			)
			(fill no)
			(layer "F.CrtYd")
		)
		(fp_line
			(start -0.3048 0.9906)
			(end 0.3048 0.9906)
			(stroke
				(width 0.1)
				(type default)
			)
			(layer "F.Fab")
		)
		(fp_line
			(start 0.3048 0.9906)
			(end 0.3048 -0.1016)
			(stroke
				(width 0.1)
				(type default)
			)
			(layer "F.Fab")
		)
		(fp_line
			(start -0.3048 -0.1016)
			(end -0.3048 0.9906)
			(stroke
				(width 0.1)
				(type default)
			)
			(layer "F.Fab")
		)
		(fp_line
			(start 0.3048 -0.1016)
			(end -0.3048 -0.1016)
			(stroke
				(width 0.1)
				(type default)
			)
			(layer "F.Fab")
		)
		(pad "1" smd rect
			(at 0 0 270)
			(size 0.508 0.508)
			(layers "F.Cu" "F.Mask" "F.Paste")
			(net "VR_P1V05_PCH_BIREF1")
		)
		(pad "2" smd rect
			(at 0 0.889 270)
			(size 0.508 0.508)
			(layers "F.Cu" "F.Mask" "F.Paste")
			(net "GND")
		)
		(zone
			(layer "F.Cu")
			(hatch none 0.5)
			(connect_pads
				(clearance 0)
			)
			(min_thickness 0.25)
			(keepout
				(tracks not_allowed)
				(vias allowed)
				(pads allowed)
				(copperpour not_allowed)
				(footprints allowed)
			)
			(placement
				(enabled no)
				(sheetname "")
			)
			(fill
				(thermal_gap 0.5)
				(thermal_bridge_width 0.5)
				(island_removal_mode 0)
			)
			(polygon
				(pts
					(xy 382.073404 -158.502858) (xy 382.073404 -157.994858) (xy 382.454404 -157.994858) (xy 382.454404 -158.502858)
				)
			)
		)
		(zone
			(layer "F.Cu")
			(hatch none 0.5)
			(connect_pads
				(clearance 0)
			)
			(min_thickness 0.25)
			(keepout
				(tracks allowed)
				(vias not_allowed)
				(pads allowed)
				(copperpour not_allowed)
				(footprints allowed)
			)
			(placement
				(enabled no)
				(sheetname "")
			)
			(fill
				(thermal_gap 0.5)
				(thermal_bridge_width 0.5)
				(island_removal_mode 0)
			)
			(polygon
				(pts
					(xy 382.454404 -158.502858) (xy 382.454404 -157.994858) (xy 382.073404 -157.994858) (xy 382.073404 -158.502858)
				)
			)
		)
	)
	(footprint ""
		(layer "F.Cu")
		(at 101.013768 -84.7598)
		(property "Reference" "C2D5"
			(at 0 0 0)
			(layer "F.SilkS")
			(hide yes)
			(effects
				(font
					(size 1.27 1.27)
				)
			)
		)
		(property "Value" ""
			(at 0 0 0)
			(layer "F.Fab")
			(effects
				(font
					(size 1.27 1.27)
				)
			)
		)
		(duplicate_pad_numbers_are_jumpers no)
		(fp_poly
			(pts
				(xy -0.4953 -0.2032) (xy 0.4953 -0.2032) (xy 0.4953 1.6002) (xy -0.4953 1.6002)
			)
			(stroke
				(width 0)
				(type default)
			)
			(fill no)
			(layer "F.CrtYd")
		)
		(fp_line
			(start -0.4953 -0.2032)
			(end 0.4953 -0.2032)
			(stroke
				(width 0.1)
				(type default)
			)
			(layer "F.Fab")
		)
		(fp_line
			(start -0.4953 1.6002)
			(end -0.4953 -0.2032)
			(stroke
				(width 0.1)
				(type default)
			)
			(layer "F.Fab")
		)
		(fp_line
			(start 0.4953 -0.2032)
			(end 0.4953 1.6002)
			(stroke
				(width 0.1)
				(type default)
			)
			(layer "F.Fab")
		)
		(fp_line
			(start 0.4953 1.6002)
			(end -0.4953 1.6002)
			(stroke
				(width 0.1)
				(type default)
			)
			(layer "F.Fab")
		)
		(pad "1" smd rect
			(at 0 0)
			(size 0.762 0.889)
			(layers "F.Cu" "F.Mask" "F.Paste")
			(net "PVDDQ_KLM")
		)
		(pad "2" smd rect
			(at 0 1.397)
			(size 0.762 0.889)
			(layers "F.Cu" "F.Mask" "F.Paste")
			(net "GND")
		)
		(zone
			(layer "F.Cu")
			(hatch none 0.5)
			(connect_pads
				(clearance 0)
			)
			(min_thickness 0.25)
			(keepout
				(tracks not_allowed)
				(vias allowed)
				(pads allowed)
				(copperpour not_allowed)
				(footprints allowed)
			)
			(placement
				(enabled no)
				(sheetname "")
			)
			(fill
				(thermal_gap 0.5)
				(thermal_bridge_width 0.5)
				(island_removal_mode 0)
			)
			(polygon
				(pts
					(xy 100.632768 -84.3153) (xy 101.394768 -84.3153) (xy 101.394768 -83.8073) (xy 100.632768 -83.8073)
				)
			)
		)
	)
	(footprint ""
		(layer "F.Cu")
		(at 253.392432 -149.8092 90)
		(property "Reference" "C5A4"
			(at 1.848866 0.752348 90)
			(unlocked yes)
			(layer "F.SilkS")
			(effects
				(font
					(size 1.27 0.9652)
					(thickness 0.1524)
				)
			)
		)
		(property "Value" ""
			(at 0 0 90)
			(layer "F.Fab")
			(effects
				(font
					(size 1.27 1.27)
				)
			)
		)
		(duplicate_pad_numbers_are_jumpers no)
		(fp_rect
			(start -0.500126 1.598422)
			(end 0.500126 -0.201422)
			(stroke
				(width 0)
				(type default)
			)
			(fill no)
			(layer "F.CrtYd")
		)
		(fp_line
			(start 0.500126 -0.201422)
			(end 0.500126 1.598422)
			(stroke
				(width 0.1)
				(type default)
			)
			(layer "F.Fab")
		)
		(fp_line
			(start -0.500126 -0.201422)
			(end 0.500126 -0.201422)
			(stroke
				(width 0.1)
				(type default)
			)
			(layer "F.Fab")
		)
		(fp_line
			(start 0.500126 1.598422)
			(end -0.500126 1.598422)
			(stroke
				(width 0.1)
				(type default)
			)
			(layer "F.Fab")
		)
		(fp_line
			(start -0.500126 1.598422)
			(end -0.500126 -0.201422)
			(stroke
				(width 0.1)
				(type default)
			)
			(layer "F.Fab")
		)
		(pad "1" smd rect
			(at 0 0)
			(size 0.889 0.9906)
			(layers "F.Cu" "F.Mask" "F.Paste")
			(net "PVDDQ_DEF")
		)
		(pad "2" smd rect
			(at 0 1.397)
			(size 0.889 0.9906)
			(layers "F.Cu" "F.Mask" "F.Paste")
			(net "GND")
		)
		(zone
			(layer "F.Cu")
			(hatch none 0.5)
			(connect_pads
				(clearance 0)
			)
			(min_thickness 0.25)
			(keepout
				(tracks not_allowed)
				(vias allowed)
				(pads allowed)
				(copperpour not_allowed)
				(footprints allowed)
			)
			(placement
				(enabled no)
				(sheetname "")
			)
			(fill
				(thermal_gap 0.5)
				(thermal_bridge_width 0.5)
				(island_removal_mode 0)
			)
			(polygon
				(pts
					(xy 254.344932 -149.3139) (xy 254.344932 -150.3045) (xy 253.836932 -150.3045) (xy 253.836932 -149.3139)
				)
			)
		)
		(zone
			(layer "F.Cu")
			(hatch none 0.5)
			(connect_pads
				(clearance 0)
			)
			(min_thickness 0.25)
			(keepout
				(tracks allowed)
				(vias not_allowed)
				(pads allowed)
				(copperpour not_allowed)
				(footprints allowed)
			)
			(placement
				(enabled no)
				(sheetname "")
			)
			(fill
				(thermal_gap 0.5)
				(thermal_bridge_width 0.5)
				(island_removal_mode 0)
			)
			(polygon
				(pts
					(xy 254.344932 -149.3139) (xy 254.344932 -150.3045) (xy 253.836932 -150.3045) (xy 253.836932 -149.3139)
				)
			)
		)
	)
	(footprint ""
		(layer "F.Cu")
		(at 206.248 -103.505 90)
		(property "Reference" "R4C2"
			(at 0 0 90)
			(layer "F.SilkS")
			(hide yes)
			(effects
				(font
					(size 1.27 1.27)
				)
			)
		)
		(property "Value" ""
			(at 0 0 90)
			(layer "F.Fab")
			(effects
				(font
					(size 1.27 1.27)
				)
			)
		)
		(duplicate_pad_numbers_are_jumpers no)
		(fp_poly
			(pts
				(xy -0.2794 -0.1016) (xy 0.2794 -0.1016) (xy 0.2794 0.9906) (xy -0.2794 0.9906)
			)
			(stroke
				(width 0)
				(type default)
			)
			(fill no)
			(layer "F.CrtYd")
		)
		(fp_line
			(start 0.2794 -0.1016)
			(end -0.2794 -0.1016)
			(stroke
				(width 0.1)
				(type default)
			)
			(layer "F.Fab")
		)
		(fp_line
			(start -0.2794 -0.1016)
			(end -0.2794 0.9906)
			(stroke
				(width 0.1)
				(type default)
			)
			(layer "F.Fab")
		)
		(fp_line
			(start 0.2794 0.9906)
			(end 0.2794 -0.1016)
			(stroke
				(width 0.1)
				(type default)
			)
			(layer "F.Fab")
		)
		(fp_line
			(start -0.2794 0.9906)
			(end 0.2794 0.9906)
			(stroke
				(width 0.1)
				(type default)
			)
			(layer "F.Fab")
		)
		(pad "1" smd rect
			(at 0 0 90)
			(size 0.508 0.508)
			(layers "F.Cu" "F.Mask" "F.Paste")
			(net "VSENSE_PVSA_CPU0_N")
		)
		(pad "2" smd rect
			(at 0 0.889 90)
			(size 0.508 0.508)
			(layers "F.Cu" "F.Mask" "F.Paste")
			(net "VSENSE_PVSA_CPU0_SKT_VRTN")
		)
		(zone
			(layer "F.Cu")
			(hatch none 0.5)
			(connect_pads
				(clearance 0)
			)
			(min_thickness 0.25)
			(keepout
				(tracks allowed)
				(vias not_allowed)
				(pads allowed)
				(copperpour not_allowed)
				(footprints allowed)
			)
			(placement
				(enabled no)
				(sheetname "")
			)
			(fill
				(thermal_gap 0.5)
				(thermal_bridge_width 0.5)
				(island_removal_mode 0)
			)
			(polygon
				(pts
					(xy 206.502 -103.251) (xy 206.502 -103.759) (xy 206.883 -103.759) (xy 206.883 -103.251)
				)
			)
		)
		(zone
			(layer "F.Cu")
			(hatch none 0.5)
			(connect_pads
				(clearance 0)
			)
			(min_thickness 0.25)
			(keepout
				(tracks not_allowed)
				(vias allowed)
				(pads allowed)
				(copperpour not_allowed)
				(footprints allowed)
			)
			(placement
				(enabled no)
				(sheetname "")
			)
			(fill
				(thermal_gap 0.5)
				(thermal_bridge_width 0.5)
				(island_removal_mode 0)
			)
			(polygon
				(pts
					(xy 206.883 -103.251) (xy 206.883 -103.759) (xy 206.502 -103.759) (xy 206.502 -103.251)
				)
			)
		)
	)
	(footprint ""
		(layer "F.Cu")
		(at 385.572 -56.3245)
		(property "Reference" "R7F30"
			(at 0 0 0)
			(layer "F.SilkS")
			(hide yes)
			(effects
				(font
					(size 1.27 1.27)
				)
			)
		)
		(property "Value" ""
			(at 0 0 0)
			(layer "F.Fab")
			(effects
				(font
					(size 1.27 1.27)
				)
			)
		)
		(duplicate_pad_numbers_are_jumpers no)
		(fp_poly
			(pts
				(xy -0.2794 -0.1016) (xy 0.2794 -0.1016) (xy 0.2794 0.9906) (xy -0.2794 0.9906)
			)
			(stroke
				(width 0)
				(type default)
			)
			(fill no)
			(layer "F.CrtYd")
		)
		(fp_line
			(start -0.2794 -0.1016)
			(end -0.2794 0.9906)
			(stroke
				(width 0.1)
				(type default)
			)
			(layer "F.Fab")
		)
		(fp_line
			(start -0.2794 0.9906)
			(end 0.2794 0.9906)
			(stroke
				(width 0.1)
				(type default)
			)
			(layer "F.Fab")
		)
		(fp_line
			(start 0.2794 -0.1016)
			(end -0.2794 -0.1016)
			(stroke
				(width 0.1)
				(type default)
			)
			(layer "F.Fab")
		)
		(fp_line
			(start 0.2794 0.9906)
			(end 0.2794 -0.1016)
			(stroke
				(width 0.1)
				(type default)
			)
			(layer "F.Fab")
		)
		(pad "1" smd rect
			(at 0 0)
			(size 0.508 0.508)
			(layers "F.Cu" "F.Mask" "F.Paste")
			(net "PU_BIOS_SPI_WP0_N")
		)
		(pad "2" smd rect
			(at 0 0.889)
			(size 0.508 0.508)
			(layers "F.Cu" "F.Mask" "F.Paste")
			(net "GND")
		)
		(zone
			(layer "F.Cu")
			(hatch none 0.5)
			(connect_pads
				(clearance 0)
			)
			(min_thickness 0.25)
			(keepout
				(tracks allowed)
				(vias not_allowed)
				(pads allowed)
				(copperpour not_allowed)
				(footprints allowed)
			)
			(placement
				(enabled no)
				(sheetname "")
			)
			(fill
				(thermal_gap 0.5)
				(thermal_bridge_width 0.5)
				(island_removal_mode 0)
			)
			(polygon
				(pts
					(xy 385.318 -56.0705) (xy 385.826 -56.0705) (xy 385.826 -55.6895) (xy 385.318 -55.6895)
				)
			)
		)
		(zone
			(layer "F.Cu")
			(hatch none 0.5)
			(connect_pads
				(clearance 0)
			)
			(min_thickness 0.25)
			(keepout
				(tracks not_allowed)
				(vias allowed)
				(pads allowed)
				(copperpour not_allowed)
				(footprints allowed)
			)
			(placement
				(enabled no)
				(sheetname "")
			)
			(fill
				(thermal_gap 0.5)
				(thermal_bridge_width 0.5)
				(island_removal_mode 0)
			)
			(polygon
				(pts
					(xy 385.318 -55.6895) (xy 385.826 -55.6895) (xy 385.826 -56.0705) (xy 385.318 -56.0705)
				)
			)
		)
	)
	(footprint ""
		(layer "F.Cu")
		(at 15.24 -86.741 180)
		(property "Reference" "R1D7"
			(at 0 0 180)
			(layer "F.SilkS")
			(hide yes)
			(effects
				(font
					(size 1.27 1.27)
				)
			)
		)
		(property "Value" ""
			(at 0 0 180)
			(layer "F.Fab")
			(effects
				(font
					(size 1.27 1.27)
				)
			)
		)
		(duplicate_pad_numbers_are_jumpers no)
		(fp_rect
			(start 0.2794 -0.1016)
			(end -0.2794 0.9906)
			(stroke
				(width 0)
				(type default)
			)
			(fill no)
			(layer "F.CrtYd")
		)
		(fp_line
			(start 0.2794 0.9906)
			(end 0.2794 -0.1016)
			(stroke
				(width 0.1)
				(type default)
			)
			(layer "F.Fab")
		)
		(fp_line
			(start 0.2794 -0.1016)
			(end -0.2794 -0.1016)
			(stroke
				(width 0.1)
				(type default)
			)
			(layer "F.Fab")
		)
		(fp_line
			(start -0.2794 0.9906)
			(end 0.2794 0.9906)
			(stroke
				(width 0.1)
				(type default)
			)
			(layer "F.Fab")
		)
		(fp_line
			(start -0.2794 -0.1016)
			(end -0.2794 0.9906)
			(stroke
				(width 0.1)
				(type default)
			)
			(layer "F.Fab")
		)
		(pad "1" smd rect
			(at 0 0 180)
			(size 0.508 0.508)
			(layers "F.Cu" "F.Mask" "F.Paste")
			(net "P3V3_STBY")
		)
		(pad "2" smd rect
			(at 0 0.889 180)
			(size 0.508 0.508)
			(layers "F.Cu" "F.Mask" "F.Paste")
			(net "FM_PVCCIN_CPU1_PWR_IN_ALERT_N")
		)
		(zone
			(layer "F.Cu")
			(hatch none 0.5)
			(connect_pads
				(clearance 0)
			)
			(min_thickness 0.25)
			(keepout
				(tracks not_allowed)
				(vias allowed)
				(pads allowed)
				(copperpour not_allowed)
				(footprints allowed)
			)
			(placement
				(enabled no)
				(sheetname "")
			)
			(fill
				(thermal_gap 0.5)
				(thermal_bridge_width 0.5)
				(island_removal_mode 0)
			)
			(polygon
				(pts
					(xy 14.986 -86.995) (xy 15.494 -86.995) (xy 15.494 -87.376) (xy 14.986 -87.376)
				)
			)
		)
		(zone
			(layer "F.Cu")
			(hatch none 0.5)
			(connect_pads
				(clearance 0)
			)
			(min_thickness 0.25)
			(keepout
				(tracks allowed)
				(vias not_allowed)
				(pads allowed)
				(copperpour not_allowed)
				(footprints allowed)
			)
			(placement
				(enabled no)
				(sheetname "")
			)
			(fill
				(thermal_gap 0.5)
				(thermal_bridge_width 0.5)
				(island_removal_mode 0)
			)
			(polygon
				(pts
					(xy 14.986 -86.995) (xy 15.494 -86.995) (xy 15.494 -87.376) (xy 14.986 -87.376)
				)
			)
		)
	)
)
